(kicad_pcb
	(version 20260206)
	(generator "pcbnew")
	(generator_version "10.0")
	(general
		(thickness 1.6)
		(legacy_teardrops no)
	)
	(paper "A4")
	(title_block
		(title "12092022_DA0F0TMDCD0_F0T_Management_Board_D_brd_V3_OCP.brd")
		(comment 1 "Grand Teton / footprints 1053-1057 of 1440")
	)
	(layers
		(0 "F.Cu" signal "TOP")
		(4 "In1.Cu" signal "GND")
		(6 "In2.Cu" signal "IN1")
		(8 "In3.Cu" signal "GND1")
		(10 "In4.Cu" signal "IN2")
		(12 "In5.Cu" signal "VCC")
		(14 "In6.Cu" signal "VCC1")
		(16 "In7.Cu" signal "IN3")
		(18 "In8.Cu" signal "GND2")
		(20 "In9.Cu" signal "IN4")
		(22 "In10.Cu" signal "GND3")
		(2 "B.Cu" signal "BOTTOM")
		(9 "F.Adhes" user "F.Adhesive")
		(11 "B.Adhes" user "B.Adhesive")
		(13 "F.Paste" user "Package Geometry/Pastemask Top")
		(15 "B.Paste" user "Package Geometry/Pastemask Bottom")
		(5 "F.SilkS" user "Ref Des/Silkscreen Top")
		(7 "B.SilkS" user "Ref Des/Silkscreen Bottom")
		(1 "F.Mask" user "Board Geometry/Soldermask Top")
		(3 "B.Mask" user "Board Geometry/Soldermask Bottom")
		(17 "Dwgs.User" user "User.Drawings")
		(19 "Cmts.User" user "User.Comments")
		(21 "Eco1.User" user "User.Eco1")
		(23 "Eco2.User" user "User.Eco2")
		(25 "Edge.Cuts" user "Board Geometry/Outline")
		(27 "Margin" user)
		(31 "F.CrtYd" user "Package Geometry/Place Bound Top")
		(29 "B.CrtYd" user "Package Geometry/Place Bound Bottom")
		(35 "F.Fab" user "Ref Des/Assembly Top")
		(33 "B.Fab" user "Ref Des/Assembly Bottom")
	)
	(footprint ""
		(layer "B.Cu")
		(at 19.431 -83.693 -90)
		(property "Reference" "R571"
			(at 0 0 90)
			(layer "B.SilkS")
			(hide yes)
			(effects
				(font
					(size 1.27 1.27)
				)
				(justify mirror)
			)
		)
		(property "Value" ""
			(at 0 0 90)
			(layer "B.Fab")
			(effects
				(font
					(size 1.27 1.27)
				)
				(justify mirror)
			)
		)
		(duplicate_pad_numbers_are_jumpers no)
		(fp_line
			(start -0.7874 0.4064)
			(end 0.7874 0.4064)
			(stroke
				(width 0.1524)
				(type default)
			)
			(layer "B.SilkS")
		)
		(fp_line
			(start 0.7874 0.4064)
			(end 0.7874 -0.4064)
			(stroke
				(width 0.1524)
				(type default)
			)
			(layer "B.SilkS")
		)
		(fp_line
			(start -0.7874 -0.4064)
			(end -0.7874 0.4064)
			(stroke
				(width 0.1524)
				(type default)
			)
			(layer "B.SilkS")
		)
		(fp_line
			(start 0.7874 -0.4064)
			(end -0.7874 -0.4064)
			(stroke
				(width 0.1524)
				(type default)
			)
			(layer "B.SilkS")
		)
		(fp_line
			(start -0.67945 0.3048)
			(end -0.120396 0.3048)
			(stroke
				(width 0.1)
				(type default)
			)
			(layer "B.Fab")
		)
		(fp_line
			(start -0.120396 0.3048)
			(end -0.120396 0.2794)
			(stroke
				(width 0.1)
				(type default)
			)
			(layer "B.Fab")
		)
		(fp_line
			(start 0.12065 0.3048)
			(end 0.67945 0.3048)
			(stroke
				(width 0.1)
				(type default)
			)
			(layer "B.Fab")
		)
		(fp_line
			(start 0.67945 0.3048)
			(end 0.67945 -0.305054)
			(stroke
				(width 0.1)
				(type default)
			)
			(layer "B.Fab")
		)
		(fp_line
			(start -0.120396 0.2794)
			(end 0.12065 0.2794)
			(stroke
				(width 0.1)
				(type default)
			)
			(layer "B.Fab")
		)
		(fp_line
			(start 0.12065 0.2794)
			(end 0.12065 0.3048)
			(stroke
				(width 0.1)
				(type default)
			)
			(layer "B.Fab")
		)
		(fp_line
			(start -0.12065 -0.2794)
			(end -0.12065 -0.3048)
			(stroke
				(width 0.1)
				(type default)
			)
			(layer "B.Fab")
		)
		(fp_line
			(start 0.12065 -0.2794)
			(end -0.12065 -0.2794)
			(stroke
				(width 0.1)
				(type default)
			)
			(layer "B.Fab")
		)
		(fp_line
			(start -0.67945 -0.3048)
			(end -0.67945 0.3048)
			(stroke
				(width 0.1)
				(type default)
			)
			(layer "B.Fab")
		)
		(fp_line
			(start -0.12065 -0.3048)
			(end -0.67945 -0.3048)
			(stroke
				(width 0.1)
				(type default)
			)
			(layer "B.Fab")
		)
		(fp_line
			(start 0.12065 -0.305054)
			(end 0.12065 -0.2794)
			(stroke
				(width 0.1)
				(type default)
			)
			(layer "B.Fab")
		)
		(fp_line
			(start 0.67945 -0.305054)
			(end 0.12065 -0.305054)
			(stroke
				(width 0.1)
				(type default)
			)
			(layer "B.Fab")
		)
		(pad "1" smd circle
			(at 0.40005 0 90)
			(size 0 0)
			(layers "B.Cu" "B.Mask" "B.Paste")
			(net "IRQ_BMC_PCH_NMI_N")
		)
		(pad "2" smd circle
			(at -0.40005 0 90)
			(size 0 0)
			(layers "B.Cu" "B.Mask" "B.Paste")
			(net "IRQ_BMC_PCH_NMI_R_N")
		)
	)
	(footprint ""
		(layer "B.Cu")
		(at 12.319 -106.426 90)
		(property "Reference" "R134"
			(at 0 0 90)
			(layer "B.SilkS")
			(hide yes)
			(effects
				(font
					(size 1.27 1.27)
				)
				(justify mirror)
			)
		)
		(property "Value" ""
			(at 0 0 90)
			(layer "B.Fab")
			(effects
				(font
					(size 1.27 1.27)
				)
				(justify mirror)
			)
		)
		(duplicate_pad_numbers_are_jumpers no)
		(fp_line
			(start 0.7874 -0.4064)
			(end -0.7874 -0.4064)
			(stroke
				(width 0.1524)
				(type default)
			)
			(layer "B.SilkS")
		)
		(fp_line
			(start -0.7874 -0.4064)
			(end -0.7874 0.4064)
			(stroke
				(width 0.1524)
				(type default)
			)
			(layer "B.SilkS")
		)
		(fp_line
			(start 0.7874 0.4064)
			(end 0.7874 -0.4064)
			(stroke
				(width 0.1524)
				(type default)
			)
			(layer "B.SilkS")
		)
		(fp_line
			(start -0.7874 0.4064)
			(end 0.7874 0.4064)
			(stroke
				(width 0.1524)
				(type default)
			)
			(layer "B.SilkS")
		)
		(fp_line
			(start 0.67945 -0.305054)
			(end 0.12065 -0.305054)
			(stroke
				(width 0.1)
				(type default)
			)
			(layer "B.Fab")
		)
		(fp_line
			(start 0.12065 -0.305054)
			(end 0.12065 -0.2794)
			(stroke
				(width 0.1)
				(type default)
			)
			(layer "B.Fab")
		)
		(fp_line
			(start -0.12065 -0.3048)
			(end -0.67945 -0.3048)
			(stroke
				(width 0.1)
				(type default)
			)
			(layer "B.Fab")
		)
		(fp_line
			(start -0.67945 -0.3048)
			(end -0.67945 0.3048)
			(stroke
				(width 0.1)
				(type default)
			)
			(layer "B.Fab")
		)
		(fp_line
			(start 0.12065 -0.2794)
			(end -0.12065 -0.2794)
			(stroke
				(width 0.1)
				(type default)
			)
			(layer "B.Fab")
		)
		(fp_line
			(start -0.12065 -0.2794)
			(end -0.12065 -0.3048)
			(stroke
				(width 0.1)
				(type default)
			)
			(layer "B.Fab")
		)
		(fp_line
			(start 0.12065 0.2794)
			(end 0.12065 0.3048)
			(stroke
				(width 0.1)
				(type default)
			)
			(layer "B.Fab")
		)
		(fp_line
			(start -0.120396 0.2794)
			(end 0.12065 0.2794)
			(stroke
				(width 0.1)
				(type default)
			)
			(layer "B.Fab")
		)
		(fp_line
			(start 0.67945 0.3048)
			(end 0.67945 -0.305054)
			(stroke
				(width 0.1)
				(type default)
			)
			(layer "B.Fab")
		)
		(fp_line
			(start 0.12065 0.3048)
			(end 0.67945 0.3048)
			(stroke
				(width 0.1)
				(type default)
			)
			(layer "B.Fab")
		)
		(fp_line
			(start -0.120396 0.3048)
			(end -0.120396 0.2794)
			(stroke
				(width 0.1)
				(type default)
			)
			(layer "B.Fab")
		)
		(fp_line
			(start -0.67945 0.3048)
			(end -0.120396 0.3048)
			(stroke
				(width 0.1)
				(type default)
			)
			(layer "B.Fab")
		)
		(pad "1" smd circle
			(at 0.40005 0 270)
			(size 0 0)
			(layers "B.Cu" "B.Mask" "B.Paste")
			(net "FM_BMC_UARTSW_LSB_N")
		)
		(pad "2" smd circle
			(at -0.40005 0 270)
			(size 0 0)
			(layers "B.Cu" "B.Mask" "B.Paste")
			(net "FM_UARTSW_LSB_N")
		)
	)
	(footprint ""
		(layer "B.Cu")
		(at 12.319 -93.472 180)
		(property "Reference" "R825"
			(at 0 0 0)
			(layer "B.SilkS")
			(hide yes)
			(effects
				(font
					(size 1.27 1.27)
				)
				(justify mirror)
			)
		)
		(property "Value" ""
			(at 0 0 0)
			(layer "B.Fab")
			(effects
				(font
					(size 1.27 1.27)
				)
				(justify mirror)
			)
		)
		(duplicate_pad_numbers_are_jumpers no)
		(fp_line
			(start 0.7874 0.4064)
			(end 0.7874 -0.4064)
			(stroke
				(width 0.1524)
				(type default)
			)
			(layer "B.SilkS")
		)
		(fp_line
			(start 0.7874 -0.4064)
			(end -0.7874 -0.4064)
			(stroke
				(width 0.1524)
				(type default)
			)
			(layer "B.SilkS")
		)
		(fp_line
			(start -0.7874 0.4064)
			(end 0.7874 0.4064)
			(stroke
				(width 0.1524)
				(type default)
			)
			(layer "B.SilkS")
		)
		(fp_line
			(start -0.7874 -0.4064)
			(end -0.7874 0.4064)
			(stroke
				(width 0.1524)
				(type default)
			)
			(layer "B.SilkS")
		)
		(fp_line
			(start 0.67945 0.3048)
			(end 0.67945 -0.305054)
			(stroke
				(width 0.1)
				(type default)
			)
			(layer "B.Fab")
		)
		(fp_line
			(start 0.67945 -0.305054)
			(end 0.12065 -0.305054)
			(stroke
				(width 0.1)
				(type default)
			)
			(layer "B.Fab")
		)
		(fp_line
			(start 0.12065 0.3048)
			(end 0.67945 0.3048)
			(stroke
				(width 0.1)
				(type default)
			)
			(layer "B.Fab")
		)
		(fp_line
			(start 0.12065 0.2794)
			(end 0.12065 0.3048)
			(stroke
				(width 0.1)
				(type default)
			)
			(layer "B.Fab")
		)
		(fp_line
			(start 0.12065 -0.2794)
			(end -0.12065 -0.2794)
			(stroke
				(width 0.1)
				(type default)
			)
			(layer "B.Fab")
		)
		(fp_line
			(start 0.12065 -0.305054)
			(end 0.12065 -0.2794)
			(stroke
				(width 0.1)
				(type default)
			)
			(layer "B.Fab")
		)
		(fp_line
			(start -0.120396 0.3048)
			(end -0.120396 0.2794)
			(stroke
				(width 0.1)
				(type default)
			)
			(layer "B.Fab")
		)
		(fp_line
			(start -0.120396 0.2794)
			(end 0.12065 0.2794)
			(stroke
				(width 0.1)
				(type default)
			)
			(layer "B.Fab")
		)
		(fp_line
			(start -0.12065 -0.2794)
			(end -0.12065 -0.3048)
			(stroke
				(width 0.1)
				(type default)
			)
			(layer "B.Fab")
		)
		(fp_line
			(start -0.12065 -0.3048)
			(end -0.67945 -0.3048)
			(stroke
				(width 0.1)
				(type default)
			)
			(layer "B.Fab")
		)
		(fp_line
			(start -0.67945 0.3048)
			(end -0.120396 0.3048)
			(stroke
				(width 0.1)
				(type default)
			)
			(layer "B.Fab")
		)
		(fp_line
			(start -0.67945 -0.3048)
			(end -0.67945 0.3048)
			(stroke
				(width 0.1)
				(type default)
			)
			(layer "B.Fab")
		)
		(pad "1" smd circle
			(at 0.40005 0)
			(size 0 0)
			(layers "B.Cu" "B.Mask" "B.Paste")
			(net "RST_ROT_CPU_N")
		)
		(pad "2" smd circle
			(at -0.40005 0)
			(size 0 0)
			(layers "B.Cu" "B.Mask" "B.Paste")
			(net "RST_ROT_CPU_R_N")
		)
	)
	(footprint ""
		(layer "B.Cu")
		(at 76.691744 -35.540188 -90)
		(property "Reference" "R337"
			(at 0 0 90)
			(layer "B.SilkS")
			(hide yes)
			(effects
				(font
					(size 1.27 1.27)
				)
				(justify mirror)
			)
		)
		(property "Value" ""
			(at 0 0 90)
			(layer "B.Fab")
			(effects
				(font
					(size 1.27 1.27)
				)
				(justify mirror)
			)
		)
		(duplicate_pad_numbers_are_jumpers no)
		(fp_line
			(start -0.7874 0.4064)
			(end 0.7874 0.4064)
			(stroke
				(width 0.1524)
				(type default)
			)
			(layer "B.SilkS")
		)
		(fp_line
			(start 0.7874 0.4064)
			(end 0.7874 -0.4064)
			(stroke
				(width 0.1524)
				(type default)
			)
			(layer "B.SilkS")
		)
		(fp_line
			(start -0.7874 -0.4064)
			(end -0.7874 0.4064)
			(stroke
				(width 0.1524)
				(type default)
			)
			(layer "B.SilkS")
		)
		(fp_line
			(start 0.7874 -0.4064)
			(end -0.7874 -0.4064)
			(stroke
				(width 0.1524)
				(type default)
			)
			(layer "B.SilkS")
		)
		(fp_line
			(start -0.67945 0.3048)
			(end -0.120396 0.3048)
			(stroke
				(width 0.1)
				(type default)
			)
			(layer "B.Fab")
		)
		(fp_line
			(start -0.120396 0.3048)
			(end -0.120396 0.2794)
			(stroke
				(width 0.1)
				(type default)
			)
			(layer "B.Fab")
		)
		(fp_line
			(start 0.12065 0.3048)
			(end 0.67945 0.3048)
			(stroke
				(width 0.1)
				(type default)
			)
			(layer "B.Fab")
		)
		(fp_line
			(start 0.67945 0.3048)
			(end 0.67945 -0.305054)
			(stroke
				(width 0.1)
				(type default)
			)
			(layer "B.Fab")
		)
		(fp_line
			(start -0.120396 0.2794)
			(end 0.12065 0.2794)
			(stroke
				(width 0.1)
				(type default)
			)
			(layer "B.Fab")
		)
		(fp_line
			(start 0.12065 0.2794)
			(end 0.12065 0.3048)
			(stroke
				(width 0.1)
				(type default)
			)
			(layer "B.Fab")
		)
		(fp_line
			(start -0.12065 -0.2794)
			(end -0.12065 -0.3048)
			(stroke
				(width 0.1)
				(type default)
			)
			(layer "B.Fab")
		)
		(fp_line
			(start 0.12065 -0.2794)
			(end -0.12065 -0.2794)
			(stroke
				(width 0.1)
				(type default)
			)
			(layer "B.Fab")
		)
		(fp_line
			(start -0.67945 -0.3048)
			(end -0.67945 0.3048)
			(stroke
				(width 0.1)
				(type default)
			)
			(layer "B.Fab")
		)
		(fp_line
			(start -0.12065 -0.3048)
			(end -0.67945 -0.3048)
			(stroke
				(width 0.1)
				(type default)
			)
			(layer "B.Fab")
		)
		(fp_line
			(start 0.12065 -0.305054)
			(end 0.12065 -0.2794)
			(stroke
				(width 0.1)
				(type default)
			)
			(layer "B.Fab")
		)
		(fp_line
			(start 0.67945 -0.305054)
			(end 0.12065 -0.305054)
			(stroke
				(width 0.1)
				(type default)
			)
			(layer "B.Fab")
		)
		(pad "1" smd circle
			(at 0.40005 0 90)
			(size 0 0)
			(layers "B.Cu" "B.Mask" "B.Paste")
			(net "GND")
		)
		(pad "2" smd circle
			(at -0.40005 0 90)
			(size 0 0)
			(layers "B.Cu" "B.Mask" "B.Paste")
			(net "M_BMC_DDR4_MA<11>")
		)
	)
	(footprint ""
		(layer "B.Cu")
		(at 77.707744 -37.559488 90)
		(property "Reference" "R357"
			(at 0 0 90)
			(layer "B.SilkS")
			(hide yes)
			(effects
				(font
					(size 1.27 1.27)
				)
				(justify mirror)
			)
		)
		(property "Value" ""
			(at 0 0 90)
			(layer "B.Fab")
			(effects
				(font
					(size 1.27 1.27)
				)
				(justify mirror)
			)
		)
		(duplicate_pad_numbers_are_jumpers no)
		(fp_line
			(start 0.7874 -0.4064)
			(end -0.7874 -0.4064)
			(stroke
				(width 0.1524)
				(type default)
			)
			(layer "B.SilkS")
		)
		(fp_line
			(start -0.7874 -0.4064)
			(end -0.7874 0.4064)
			(stroke
				(width 0.1524)
				(type default)
			)
			(layer "B.SilkS")
		)
		(fp_line
			(start 0.7874 0.4064)
			(end 0.7874 -0.4064)
			(stroke
				(width 0.1524)
				(type default)
			)
			(layer "B.SilkS")
		)
		(fp_line
			(start -0.7874 0.4064)
			(end 0.7874 0.4064)
			(stroke
				(width 0.1524)
				(type default)
			)
			(layer "B.SilkS")
		)
		(fp_line
			(start 0.67945 -0.305054)
			(end 0.12065 -0.305054)
			(stroke
				(width 0.1)
				(type default)
			)
			(layer "B.Fab")
		)
		(fp_line
			(start 0.12065 -0.305054)
			(end 0.12065 -0.2794)
			(stroke
				(width 0.1)
				(type default)
			)
			(layer "B.Fab")
		)
		(fp_line
			(start -0.12065 -0.3048)
			(end -0.67945 -0.3048)
			(stroke
				(width 0.1)
				(type default)
			)
			(layer "B.Fab")
		)
		(fp_line
			(start -0.67945 -0.3048)
			(end -0.67945 0.3048)
			(stroke
				(width 0.1)
				(type default)
			)
			(layer "B.Fab")
		)
		(fp_line
			(start 0.12065 -0.2794)
			(end -0.12065 -0.2794)
			(stroke
				(width 0.1)
				(type default)
			)
			(layer "B.Fab")
		)
		(fp_line
			(start -0.12065 -0.2794)
			(end -0.12065 -0.3048)
			(stroke
				(width 0.1)
				(type default)
			)
			(layer "B.Fab")
		)
		(fp_line
			(start 0.12065 0.2794)
			(end 0.12065 0.3048)
			(stroke
				(width 0.1)
				(type default)
			)
			(layer "B.Fab")
		)
		(fp_line
			(start -0.120396 0.2794)
			(end 0.12065 0.2794)
			(stroke
				(width 0.1)
				(type default)
			)
			(layer "B.Fab")
		)
		(fp_line
			(start 0.67945 0.3048)
			(end 0.67945 -0.305054)
			(stroke
				(width 0.1)
				(type default)
			)
			(layer "B.Fab")
		)
		(fp_line
			(start 0.12065 0.3048)
			(end 0.67945 0.3048)
			(stroke
				(width 0.1)
				(type default)
			)
			(layer "B.Fab")
		)
		(fp_line
			(start -0.120396 0.3048)
			(end -0.120396 0.2794)
			(stroke
				(width 0.1)
				(type default)
			)
			(layer "B.Fab")
		)
		(fp_line
			(start -0.67945 0.3048)
			(end -0.120396 0.3048)
			(stroke
				(width 0.1)
				(type default)
			)
			(layer "B.Fab")
		)
		(pad "1" smd circle
			(at 0.40005 0 270)
			(size 0 0)
			(layers "B.Cu" "B.Mask" "B.Paste")
			(net "M_BMC_DDR4_MA<6>")
		)
		(pad "2" smd circle
			(at -0.40005 0 270)
			(size 0 0)
			(layers "B.Cu" "B.Mask" "B.Paste")
			(net "P1V2_AUX")
		)
	)
)
